M48
INCH,TZ
T01C.008
T02C.01
T03C.012
T04C.01456
T05C.016
T06C.02244
T07C.03
T08C.032
T09C.035
T010C.036
T011C.038
T012C.04
T013C.042
T014C.05
T015C.062
T016C.086
T017C.087
T018C.091
T019C.126
T020C.128
T021C.15
T022C.168
;EXTENTS: -60.430 -67.074 51.778  45.027  
;LEADER: 12 
;HEADER: 
;CODE  : ASCII 
;FILE  : 15105-sa.rou for board 15105-sa.brd
%
G90
F1
M16
G40
M30
